#ISCELL
  mstr_misc dns *
  *
#ISCELL
  pure_quanta quanta_title_block_c *
  *
#ISCELL
  standard offpage *
  page188_i1
#CELL
  pure_quanta q_cap *
  page188_i10
#ISCELL
  standard offpage *
  page188_i11
#CELL
  pure_quanta q_res *
  page188_i12
#ISCELL
  pure_quanta_power universal_gnd *
  page188_i13
#ISCELL
  pure_quanta_power vcc_core *
  page188_i14
#CELL
  pure_quanta q_cap *
  page188_i15
#ISCELL
  pure_quanta_power universal_gnd *
  page188_i16
#ISCELL
  standard offpage *
  page188_i17
#CELL
  pure_quanta isl99390frztr5935 *
  page188_i18
#ISCELL
  pure_quanta_power universal_gnd *
  page188_i19
#ISCELL
  standard offpage *
  page188_i2
#ISCELL
  pure_quanta_power universal_gnd *
  page188_i20
#CELL
  pure_quanta q_res *
  page188_i21
#CELL
  pure_quanta q_res *
  page188_i22
#CELL
  pure_quanta q_cap *
  page188_i23
#ISCELL
  pure_quanta_power universal_gnd *
  page188_i24
#CELL
  pure_quanta q_cap *
  page188_i25
#ISCELL
  pure_quanta_power universal_gnd *
  page188_i26
#CELL
  pure_quanta q_cap *
  page188_i27
#CELL
  pure_quanta q_res *
  page188_i28
#CELL
  pure_quanta q_cap *
  page188_i29
#ISCELL
  pure_quanta_power universal_gnd *
  page188_i3
#CELL
  pure_quanta q_cap *
  page188_i30
#ISCELL
  pure_quanta_power universal_gnd *
  page188_i31
#CELL
  pure_quanta q_res *
  page188_i32
#CELL
  pure_quanta q_res *
  page188_i33
#CELL
  pure_quanta q_cap *
  page188_i34
#ISCELL
  pure_quanta_power universal_gnd *
  page188_i35
#ISCELL
  standard offpage *
  page188_i36
#CELL
  pure_quanta q_res *
  page188_i37
#ISCELL
  pure_quanta_power universal_gnd *
  page188_i38
#CELL
  pure_quanta q_cap *
  page188_i39
#CELL
  pure_quanta q_cap *
  page188_i4
#ISCELL
  standard offpage *
  page188_i40
#CELL
  pure_quanta q_res *
  page188_i41
#ISCELL
  pure_quanta_power universal_gnd *
  page188_i42
#CELL
  pure_quanta q_cap *
  page188_i43
#ISCELL
  pure_quanta_power vcc_core *
  page188_i44
#CELL
  pure_quanta q_cap *
  page188_i45
#CELL
  pure_quanta q_cap *
  page188_i46
#CELL
  pure_quanta q_res *
  page188_i47
#CELL
  pure_quanta q_cap *
  page188_i48
#CELL
  pure_quanta q_cap *
  page188_i49
#ISCELL
  pure_quanta_power universal_gnd *
  page188_i5
#CELL
  pure_quanta q_cap *
  page188_i50
#CELL
  pure_quanta q_inductor *
  page188_i51
#CELL
  pure_quanta q_cap *
  page188_i52
#CELL
  pure_quanta q_inductor4p_14 *
  page188_i53
#ISCELL
  pure_quanta_power universal_gnd *
  page188_i54
#CELL
  pure_quanta q_cap *
  page188_i55
#ISCELL
  pure_quanta_power vcc_core *
  page188_i56
#ISCELL
  standard offpage *
  page188_i57
#CELL
  pure_quanta q_cap *
  page188_i58
#ISCELL
  pure_quanta_power universal_gnd *
  page188_i59
#ISCELL
  standard offpage *
  page188_i6
#CELL
  pure_quanta q_cap *
  page188_i60
#ISCELL
  pure_quanta_power vcc_core *
  page188_i61
#ISCELL
  standard offpage *
  page188_i62
#CELL
  pure_quanta q_cap *
  page188_i63
#CELL
  pure_quanta q_inductor4p_14 *
  page188_i64
#ISCELL
  pure_quanta_power universal_gnd *
  page188_i65
#CELL
  pure_quanta q_cap *
  page188_i66
#ISCELL
  pure_quanta_power vcc_core *
  page188_i67
#ISCELL
  standard offpage *
  page188_i68
#CELL
  pure_quanta q_cap *
  page188_i69
#ISCELL
  standard offpage *
  page188_i7
#ISCELL
  pure_quanta_power universal_gnd *
  page188_i70
#CELL
  pure_quanta q_cap *
  page188_i71
#ISCELL
  pure_quanta_power vcc_core *
  page188_i72
#CELL
  pure_quanta isl99390frztr5935 *
  page188_i73
#CELL
  pure_quanta q_res *
  page188_i8
#ISCELL
  pure_quanta_power universal_gnd *
  page188_i9
